# S9S_MB_2U (Grand Teton) — schematic netlist excerpt (pin names and nets, part order shuffled) for the footprints in the layout excerpt that follows; sources: Cadence DE-HDL packaged netlist, KiCad conversion of 03242023_DA0F0TMBIJ0_F0T_Motherboard_J_brd_V01_OCP.brd

C466  Q_CAP  47UF 4V 20% X6S  pkg C0805  page 79 : A = PVCCFA_EHV_FIVRA_CPU1 ; B = GND
R3878  Q_RES  49.9 1% CHIP  pkg 0402LF  page 85 : A = I3C_SPD_DDRABCD_CPU0_LVC1_SCL_3 ; B = I3C_SPD_DDRABCD_CPU0_LVC1_SCL
C1235  Q_CAP  0.1UF 25V 10% X7R  pkg 0402  page 153 : A = P12V_OCP_SFF ; B = GND

(kicad_pcb
	(version 20260206)
	(generator "pcbnew")
	(generator_version "10.0")
	(general
		(thickness 1.6)
		(legacy_teardrops no)
	)
	(paper "A4")
	(title_block
		(title "03242023_DA0F0TMBIJ0_F0T_Motherboard_J_brd_V01_OCP.brd")
		(comment 1 "Grand Teton / footprints 6025-6027 of 6105")
	)
	(layers
		(0 "F.Cu" signal "TOP")
		(4 "In1.Cu" signal "GND")
		(6 "In2.Cu" signal "IN1")
		(8 "In3.Cu" signal "GND1")
		(10 "In4.Cu" signal "IN2")
		(12 "In5.Cu" signal "GND2")
		(14 "In6.Cu" signal "IN3")
		(16 "In7.Cu" signal "GND3")
		(18 "In8.Cu" signal "VCC")
		(20 "In9.Cu" signal "VCC1")
		(22 "In10.Cu" signal "GND4")
		(24 "In11.Cu" signal "IN4")
		(26 "In12.Cu" signal "GND5")
		(28 "In13.Cu" signal "IN5")
		(30 "In14.Cu" signal "GND6")
		(32 "In15.Cu" signal "IN6")
		(34 "In16.Cu" signal "GND7")
		(2 "B.Cu" signal "BOTTOM")
		(9 "F.Adhes" user "F.Adhesive")
		(11 "B.Adhes" user "B.Adhesive")
		(13 "F.Paste" user "Package Geometry/Pastemask Top")
		(15 "B.Paste" user "Package Geometry/Pastemask Bottom")
		(5 "F.SilkS" user "Ref Des/Silkscreen Top")
		(7 "B.SilkS" user "Ref Des/Silkscreen Bottom")
		(1 "F.Mask" user "Board Geometry/Soldermask Top")
		(3 "B.Mask" user "Board Geometry/Soldermask Bottom")
		(17 "Dwgs.User" user "User.Drawings")
		(19 "Cmts.User" user "User.Comments")
		(21 "Eco1.User" user "User.Eco1")
		(23 "Eco2.User" user "User.Eco2")
		(25 "Edge.Cuts" user "Board Geometry/Outline")
		(27 "Margin" user)
		(31 "F.CrtYd" user "Package Geometry/Place Bound Top")
		(29 "B.CrtYd" user "Package Geometry/Place Bound Bottom")
		(35 "F.Fab" user "Ref Des/Assembly Top")
		(33 "B.Fab" user "Ref Des/Assembly Bottom")
	)
	(footprint ""
		(layer "B.Cu")
		(at 440.395868 -16.700246)
		(property "Reference" "C1235"
			(at 0 0 0)
			(layer "B.SilkS")
			(hide yes)
			(effects
				(font
					(size 1.27 1.27)
				)
				(justify mirror)
			)
		)
		(property "Value" ""
			(at 0 0 0)
			(layer "B.Fab")
			(effects
				(font
					(size 1.27 1.27)
				)
				(justify mirror)
			)
		)
		(duplicate_pad_numbers_are_jumpers no)
		(fp_line
			(start -0.7874 -0.4064)
			(end -0.7874 0.4064)
			(stroke
				(width 0.1524)
				(type default)
			)
			(layer "B.SilkS")
		)
		(fp_line
			(start -0.7874 0.4064)
			(end 0.7874 0.4064)
			(stroke
				(width 0.1524)
				(type default)
			)
			(layer "B.SilkS")
		)
		(fp_line
			(start 0.7874 -0.4064)
			(end -0.7874 -0.4064)
			(stroke
				(width 0.1524)
				(type default)
			)
			(layer "B.SilkS")
		)
		(fp_line
			(start 0.7874 0.4064)
			(end 0.7874 -0.4064)
			(stroke
				(width 0.1524)
				(type default)
			)
			(layer "B.SilkS")
		)
		(fp_line
			(start -0.67945 -0.3048)
			(end -0.67945 0.3048)
			(stroke
				(width 0.1)
				(type default)
			)
			(layer "B.Fab")
		)
		(fp_line
			(start -0.67945 0.3048)
			(end -0.120396 0.3048)
			(stroke
				(width 0.1)
				(type default)
			)
			(layer "B.Fab")
		)
		(fp_line
			(start -0.12065 -0.3048)
			(end -0.67945 -0.3048)
			(stroke
				(width 0.1)
				(type default)
			)
			(layer "B.Fab")
		)
		(fp_line
			(start -0.12065 -0.2794)
			(end -0.12065 -0.3048)
			(stroke
				(width 0.1)
				(type default)
			)
			(layer "B.Fab")
		)
		(fp_line
			(start -0.120396 0.2794)
			(end 0.12065 0.2794)
			(stroke
				(width 0.1)
				(type default)
			)
			(layer "B.Fab")
		)
		(fp_line
			(start -0.120396 0.3048)
			(end -0.120396 0.2794)
			(stroke
				(width 0.1)
				(type default)
			)
			(layer "B.Fab")
		)
		(fp_line
			(start 0.12065 -0.305054)
			(end 0.12065 -0.2794)
			(stroke
				(width 0.1)
				(type default)
			)
			(layer "B.Fab")
		)
		(fp_line
			(start 0.12065 -0.2794)
			(end -0.12065 -0.2794)
			(stroke
				(width 0.1)
				(type default)
			)
			(layer "B.Fab")
		)
		(fp_line
			(start 0.12065 0.2794)
			(end 0.12065 0.3048)
			(stroke
				(width 0.1)
				(type default)
			)
			(layer "B.Fab")
		)
		(fp_line
			(start 0.12065 0.3048)
			(end 0.67945 0.3048)
			(stroke
				(width 0.1)
				(type default)
			)
			(layer "B.Fab")
		)
		(fp_line
			(start 0.67945 -0.305054)
			(end 0.12065 -0.305054)
			(stroke
				(width 0.1)
				(type default)
			)
			(layer "B.Fab")
		)
		(fp_line
			(start 0.67945 0.3048)
			(end 0.67945 -0.305054)
			(stroke
				(width 0.1)
				(type default)
			)
			(layer "B.Fab")
		)
		(pad "1" smd circle
			(at 0.40005 0 180)
			(size 0 0)
			(layers "B.Cu" "B.Mask" "B.Paste")
			(net "P12V_OCP_SFF")
		)
		(pad "2" smd circle
			(at -0.40005 0 180)
			(size 0 0)
			(layers "B.Cu" "B.Mask" "B.Paste")
			(net "GND")
		)
	)
	(footprint ""
		(layer "B.Cu")
		(at 292.075362 -317.203836 90)
		(property "Reference" "R3878"
			(at 0 0 90)
			(layer "B.SilkS")
			(hide yes)
			(effects
				(font
					(size 1.27 1.27)
				)
				(justify mirror)
			)
		)
		(property "Value" ""
			(at 0 0 90)
			(layer "B.Fab")
			(effects
				(font
					(size 1.27 1.27)
				)
				(justify mirror)
			)
		)
		(duplicate_pad_numbers_are_jumpers no)
		(fp_line
			(start 0.7874 -0.4064)
			(end -0.7874 -0.4064)
			(stroke
				(width 0.1524)
				(type default)
			)
			(layer "B.SilkS")
		)
		(fp_line
			(start -0.7874 -0.4064)
			(end -0.7874 0.4064)
			(stroke
				(width 0.1524)
				(type default)
			)
			(layer "B.SilkS")
		)
		(fp_line
			(start 0.7874 0.4064)
			(end 0.7874 -0.4064)
			(stroke
				(width 0.1524)
				(type default)
			)
			(layer "B.SilkS")
		)
		(fp_line
			(start -0.7874 0.4064)
			(end 0.7874 0.4064)
			(stroke
				(width 0.1524)
				(type default)
			)
			(layer "B.SilkS")
		)
		(fp_line
			(start 0.67945 -0.305054)
			(end 0.12065 -0.305054)
			(stroke
				(width 0.1)
				(type default)
			)
			(layer "B.Fab")
		)
		(fp_line
			(start 0.12065 -0.305054)
			(end 0.12065 -0.2794)
			(stroke
				(width 0.1)
				(type default)
			)
			(layer "B.Fab")
		)
		(fp_line
			(start -0.12065 -0.3048)
			(end -0.67945 -0.3048)
			(stroke
				(width 0.1)
				(type default)
			)
			(layer "B.Fab")
		)
		(fp_line
			(start -0.67945 -0.3048)
			(end -0.67945 0.3048)
			(stroke
				(width 0.1)
				(type default)
			)
			(layer "B.Fab")
		)
		(fp_line
			(start 0.12065 -0.2794)
			(end -0.12065 -0.2794)
			(stroke
				(width 0.1)
				(type default)
			)
			(layer "B.Fab")
		)
		(fp_line
			(start -0.12065 -0.2794)
			(end -0.12065 -0.3048)
			(stroke
				(width 0.1)
				(type default)
			)
			(layer "B.Fab")
		)
		(fp_line
			(start 0.12065 0.2794)
			(end 0.12065 0.3048)
			(stroke
				(width 0.1)
				(type default)
			)
			(layer "B.Fab")
		)
		(fp_line
			(start -0.120396 0.2794)
			(end 0.12065 0.2794)
			(stroke
				(width 0.1)
				(type default)
			)
			(layer "B.Fab")
		)
		(fp_line
			(start 0.67945 0.3048)
			(end 0.67945 -0.305054)
			(stroke
				(width 0.1)
				(type default)
			)
			(layer "B.Fab")
		)
		(fp_line
			(start 0.12065 0.3048)
			(end 0.67945 0.3048)
			(stroke
				(width 0.1)
				(type default)
			)
			(layer "B.Fab")
		)
		(fp_line
			(start -0.120396 0.3048)
			(end -0.120396 0.2794)
			(stroke
				(width 0.1)
				(type default)
			)
			(layer "B.Fab")
		)
		(fp_line
			(start -0.67945 0.3048)
			(end -0.120396 0.3048)
			(stroke
				(width 0.1)
				(type default)
			)
			(layer "B.Fab")
		)
		(pad "1" smd circle
			(at 0.40005 0 270)
			(size 0 0)
			(layers "B.Cu" "B.Mask" "B.Paste")
			(net "I3C_SPD_DDRABCD_CPU0_LVC1_SCL_3")
		)
		(pad "2" smd circle
			(at -0.40005 0 270)
			(size 0 0)
			(layers "B.Cu" "B.Mask" "B.Paste")
			(net "I3C_SPD_DDRABCD_CPU0_LVC1_SCL")
		)
	)
	(footprint ""
		(layer "B.Cu")
		(at 57.517792 -257.918712 -90)
		(property "Reference" "C466"
			(at 0 0 90)
			(layer "B.SilkS")
			(hide yes)
			(effects
				(font
					(size 1.27 1.27)
				)
				(justify mirror)
			)
		)
		(property "Value" ""
			(at 0 0 90)
			(layer "B.Fab")
			(effects
				(font
					(size 1.27 1.27)
				)
				(justify mirror)
			)
		)
		(duplicate_pad_numbers_are_jumpers no)
		(fp_line
			(start -1.524 0.762)
			(end 1.524 0.762)
			(stroke
				(width 0.1524)
				(type default)
			)
			(layer "B.SilkS")
		)
		(fp_line
			(start 1.524 0.762)
			(end 1.524 -0.762)
			(stroke
				(width 0.1524)
				(type default)
			)
			(layer "B.SilkS")
		)
		(fp_line
			(start -1.524 -0.762)
			(end -1.524 0.762)
			(stroke
				(width 0.1524)
				(type default)
			)
			(layer "B.SilkS")
		)
		(fp_line
			(start 1.524 -0.762)
			(end -1.524 -0.762)
			(stroke
				(width 0.1524)
				(type default)
			)
			(layer "B.SilkS")
		)
		(fp_line
			(start -1.1049 0.724916)
			(end -1.1049 -0.724916)
			(stroke
				(width 0.1)
				(type default)
			)
			(layer "B.Fab")
		)
		(fp_line
			(start 1.1049 0.724916)
			(end -1.1049 0.724916)
			(stroke
				(width 0.1)
				(type default)
			)
			(layer "B.Fab")
		)
		(fp_line
			(start -1.1049 -0.724916)
			(end 1.1049 -0.724916)
			(stroke
				(width 0.1)
				(type default)
			)
			(layer "B.Fab")
		)
		(fp_line
			(start 1.1049 -0.724916)
			(end 1.1049 0.724916)
			(stroke
				(width 0.1)
				(type default)
			)
			(layer "B.Fab")
		)
		(pad "1" smd rect
			(at 0.889 0 270)
			(size 1.016 1.27)
			(layers "B.Cu" "B.Mask" "B.Paste")
			(net "PVCCFA_EHV_FIVRA_CPU1")
		)
		(pad "2" smd rect
			(at -0.889 0 270)
			(size 1.016 1.27)
			(layers "B.Cu" "B.Mask" "B.Paste")
			(net "GND")
		)
	)
)
